(kicad_pcb
	(version 20260206)
	(generator "pcbnew")
	(generator_version "10.0")
	(general
		(thickness 1.6)
		(legacy_teardrops no)
	)
	(paper "A4")
	(title_block
		(title "01162023_DA0F0TEBIF0_F0T_Expander_BD_F_brd_V02_OCP.brd")
		(comment 1 "Grand Teton / footprint 6364 of 9728 (J7), pads 1-77 of 142")
	)
	(layers
		(0 "F.Cu" signal "TOP")
		(4 "In1.Cu" signal "GND")
		(6 "In2.Cu" signal "VCC")
		(8 "In3.Cu" signal "VCC1")
		(10 "In4.Cu" signal "GND1")
		(12 "In5.Cu" signal "IN1")
		(14 "In6.Cu" signal "GND2")
		(16 "In7.Cu" signal "IN2")
		(18 "In8.Cu" signal "GND3")
		(20 "In9.Cu" signal "IN3")
		(22 "In10.Cu" signal "GND4")
		(24 "In11.Cu" signal "IN4")
		(26 "In12.Cu" signal "GND5")
		(28 "In13.Cu" signal "IN5")
		(30 "In14.Cu" signal "GND6")
		(32 "In15.Cu" signal "IN6")
		(34 "In16.Cu" signal "GND7")
		(2 "B.Cu" signal "BOTTOM")
		(9 "F.Adhes" user "F.Adhesive")
		(11 "B.Adhes" user "B.Adhesive")
		(13 "F.Paste" user "Package Geometry/Pastemask Top")
		(15 "B.Paste" user "Package Geometry/Pastemask Bottom")
		(5 "F.SilkS" user "Ref Des/Silkscreen Top")
		(7 "B.SilkS" user "Ref Des/Silkscreen Bottom")
		(1 "F.Mask" user "Board Geometry/Soldermask Top")
		(3 "B.Mask" user "Board Geometry/Soldermask Bottom")
		(17 "Dwgs.User" user "User.Drawings")
		(19 "Cmts.User" user "User.Comments")
		(21 "Eco1.User" user "User.Eco1")
		(23 "Eco2.User" user "User.Eco2")
		(25 "Edge.Cuts" user "Board Geometry/Outline")
		(27 "Margin" user)
		(31 "F.CrtYd" user "Package Geometry/Place Bound Top")
		(29 "B.CrtYd" user "Package Geometry/Place Bound Bottom")
		(35 "F.Fab" user "Ref Des/Assembly Top")
		(33 "B.Fab" user "Ref Des/Assembly Bottom")
	)
	(footprint ""
		(layer "F.Cu")
		(at 287.4899 -412.090108)
		(property "Reference" "J7"
			(at 26.271728 5.314696 90)
			(unlocked yes)
			(layer "F.SilkS")
			(effects
				(font
					(size 2.032 1.524)
					(thickness 0.1524)
				)
				(justify left)
			)
		)
		(property "Value" ""
			(at 0 0 0)
			(layer "F.Fab")
			(effects
				(font
					(size 1.27 1.27)
				)
			)
		)
		(duplicate_pad_numbers_are_jumpers no)
		(pad "A1" thru_hole rect
			(at 0 0 180)
			(size 0.71628 0.71628)
			(drill 0.30988)
			(layers "*.Cu" "*.Mask")
			(remove_unused_layers no)
			(net "GPU_3V3IO_RSVD3_FFU")
			(clearance 0.0508)
			(thermal_gap 0.0508)
			(padstack
				(mode front_inner_back)
				(layer "Inner"
					(shape circle)
					(size 0.71628 0.71628)
					(clearance 0.0508)
				)
				(layer "B.Cu"
					(shape rect)
					(size 0.71628 0.71628)
					(clearance 0.0508)
				)
			)
		)
		(pad "A2" thru_hole circle
			(at 2.199894 0.199898 180)
			(size 0.906272 0.906272)
			(drill 0.499872)
			(layers "*.Cu" "*.Mask")
			(remove_unused_layers no)
			(net "GND")
			(clearance 0.0508)
			(thermal_gap 0.0508)
		)
		(pad "A3" thru_hole circle
			(at 4.400042 0 180)
			(size 0.71628 0.71628)
			(drill 0.30988)
			(layers "*.Cu" "*.Mask")
			(remove_unused_layers no)
			(net "PRSNT_GPU_A2_N")
			(clearance 0.0508)
			(thermal_gap 0.0508)
		)
		(pad "A4" thru_hole circle
			(at 6.599936 0.199898 180)
			(size 0.906272 0.906272)
			(drill 0.499872)
			(layers "*.Cu" "*.Mask")
			(remove_unused_layers no)
			(net "GND")
			(clearance 0.0508)
			(thermal_gap 0.0508)
		)
		(pad "A5" thru_hole circle
			(at 8.800084 0 180)
			(size 0.71628 0.71628)
			(drill 0.30988)
			(layers "*.Cu" "*.Mask")
			(remove_unused_layers no)
			(net "GPU_3V3IO_RSVD5_FFU")
			(clearance 0.0508)
			(thermal_gap 0.0508)
		)
		(pad "A6" thru_hole circle
			(at 10.999978 0.199898 180)
			(size 0.906272 0.906272)
			(drill 0.499872)
			(layers "*.Cu" "*.Mask")
			(remove_unused_layers no)
			(net "GND")
			(clearance 0.0508)
			(thermal_gap 0.0508)
		)
		(pad "A7" thru_hole circle
			(at 13.199872 0 180)
			(size 0.71628 0.71628)
			(drill 0.30988)
			(layers "*.Cu" "*.Mask")
			(remove_unused_layers no)
			(net "GPU_FPGA_OVERT_N")
			(clearance 0.0508)
			(thermal_gap 0.0508)
		)
		(pad "A8" thru_hole circle
			(at 15.40002 0.199898 180)
			(size 0.906272 0.906272)
			(drill 0.499872)
			(layers "*.Cu" "*.Mask")
			(remove_unused_layers no)
			(net "GND")
			(clearance 0.0508)
			(thermal_gap 0.0508)
		)
		(pad "A9" thru_hole circle
			(at 17.599914 0 180)
			(size 0.71628 0.71628)
			(drill 0.30988)
			(layers "*.Cu" "*.Mask")
			(remove_unused_layers no)
			(net "Net_8815")
			(clearance 0.0508)
			(thermal_gap 0.0508)
		)
		(pad "A10" thru_hole circle
			(at 19.800062 0.199898 180)
			(size 0.906272 0.906272)
			(drill 0.499872)
			(layers "*.Cu" "*.Mask")
			(remove_unused_layers no)
			(net "GND")
			(clearance 0.0508)
			(thermal_gap 0.0508)
		)
		(pad "B1" thru_hole circle
			(at 0 1.299972 180)
			(size 0.906272 0.906272)
			(drill 0.499872)
			(layers "*.Cu" "*.Mask")
			(remove_unused_layers no)
			(net "GND")
			(clearance 0.0508)
			(thermal_gap 0.0508)
		)
		(pad "B3" thru_hole circle
			(at 4.400042 1.299972 180)
			(size 0.906272 0.906272)
			(drill 0.499872)
			(layers "*.Cu" "*.Mask")
			(remove_unused_layers no)
			(net "GND")
			(clearance 0.0508)
			(thermal_gap 0.0508)
		)
		(pad "B5" thru_hole circle
			(at 8.800084 1.299972 180)
			(size 0.906272 0.906272)
			(drill 0.499872)
			(layers "*.Cu" "*.Mask")
			(remove_unused_layers no)
			(net "GND")
			(clearance 0.0508)
			(thermal_gap 0.0508)
		)
		(pad "B7" thru_hole circle
			(at 13.199872 1.299972 180)
			(size 0.906272 0.906272)
			(drill 0.499872)
			(layers "*.Cu" "*.Mask")
			(remove_unused_layers no)
			(net "GND")
			(clearance 0.0508)
			(thermal_gap 0.0508)
		)
		(pad "B9" thru_hole circle
			(at 17.599914 1.299972 180)
			(size 0.906272 0.906272)
			(drill 0.499872)
			(layers "*.Cu" "*.Mask")
			(remove_unused_layers no)
			(net "GND")
			(clearance 0.0508)
			(thermal_gap 0.0508)
		)
		(pad "B10" thru_hole circle
			(at 19.800062 1.500124 180)
			(size 0.71628 0.71628)
			(drill 0.30988)
			(layers "*.Cu" "*.Mask")
			(remove_unused_layers no)
			(net "Net_8814")
			(clearance 0.0508)
			(thermal_gap 0.0508)
		)
		(pad "C9" thru_hole circle
			(at 17.599914 2.599944 180)
			(size 0.71628 0.71628)
			(drill 0.30988)
			(layers "*.Cu" "*.Mask")
			(remove_unused_layers no)
			(net "Net_8812")
			(clearance 0.0508)
			(thermal_gap 0.0508)
		)
		(pad "C10" thru_hole circle
			(at 19.800062 2.800096 180)
			(size 0.71628 0.71628)
			(drill 0.30988)
			(layers "*.Cu" "*.Mask")
			(remove_unused_layers no)
			(net "Net_8813")
			(clearance 0.0508)
			(thermal_gap 0.0508)
		)
		(pad "D2" thru_hole circle
			(at 2.199894 4.100068 180)
			(size 0.906272 0.906272)
			(drill 0.499872)
			(layers "*.Cu" "*.Mask")
			(remove_unused_layers no)
			(net "GND")
			(clearance 0.0508)
			(thermal_gap 0.0508)
		)
		(pad "D4" thru_hole circle
			(at 6.599936 4.100068 180)
			(size 0.906272 0.906272)
			(drill 0.499872)
			(layers "*.Cu" "*.Mask")
			(remove_unused_layers no)
			(net "GND")
			(clearance 0.0508)
			(thermal_gap 0.0508)
		)
		(pad "D6" thru_hole circle
			(at 10.999978 4.100068 180)
			(size 0.906272 0.906272)
			(drill 0.499872)
			(layers "*.Cu" "*.Mask")
			(remove_unused_layers no)
			(net "GND")
			(clearance 0.0508)
			(thermal_gap 0.0508)
		)
		(pad "D8" thru_hole circle
			(at 15.40002 4.100068 180)
			(size 0.906272 0.906272)
			(drill 0.499872)
			(layers "*.Cu" "*.Mask")
			(remove_unused_layers no)
			(net "GND")
			(clearance 0.0508)
			(thermal_gap 0.0508)
		)
		(pad "D9" thru_hole circle
			(at 17.599914 3.899916 180)
			(size 0.71628 0.71628)
			(drill 0.30988)
			(layers "*.Cu" "*.Mask")
			(remove_unused_layers no)
			(net "Net_8811")
			(clearance 0.0508)
			(thermal_gap 0.0508)
		)
		(pad "D10" thru_hole circle
			(at 19.800062 4.100068 180)
			(size 0.906272 0.906272)
			(drill 0.499872)
			(layers "*.Cu" "*.Mask")
			(remove_unused_layers no)
			(net "GND")
			(clearance 0.0508)
			(thermal_gap 0.0508)
		)
		(pad "E1" thru_hole circle
			(at 0 5.199888 180)
			(size 0.906272 0.906272)
			(drill 0.499872)
			(layers "*.Cu" "*.Mask")
			(remove_unused_layers no)
			(net "GND")
			(clearance 0.0508)
			(thermal_gap 0.0508)
		)
		(pad "E3" thru_hole circle
			(at 4.400042 5.199888 180)
			(size 0.906272 0.906272)
			(drill 0.499872)
			(layers "*.Cu" "*.Mask")
			(remove_unused_layers no)
			(net "GND")
			(clearance 0.0508)
			(thermal_gap 0.0508)
		)
		(pad "E5" thru_hole circle
			(at 8.800084 5.199888 180)
			(size 0.906272 0.906272)
			(drill 0.499872)
			(layers "*.Cu" "*.Mask")
			(remove_unused_layers no)
			(net "GND")
			(clearance 0.0508)
			(thermal_gap 0.0508)
		)
		(pad "E7" thru_hole circle
			(at 13.199872 5.199888 180)
			(size 0.906272 0.906272)
			(drill 0.499872)
			(layers "*.Cu" "*.Mask")
			(remove_unused_layers no)
			(net "GND")
			(clearance 0.0508)
			(thermal_gap 0.0508)
		)
		(pad "E9" thru_hole circle
			(at 17.599914 5.199888 180)
			(size 0.906272 0.906272)
			(drill 0.499872)
			(layers "*.Cu" "*.Mask")
			(remove_unused_layers no)
			(net "GND")
			(clearance 0.0508)
			(thermal_gap 0.0508)
		)
		(pad "E10" thru_hole circle
			(at 19.800062 5.40004 180)
			(size 0.71628 0.71628)
			(drill 0.30988)
			(layers "*.Cu" "*.Mask")
			(remove_unused_layers no)
			(net "Net_8810")
			(clearance 0.0508)
			(thermal_gap 0.0508)
		)
		(pad "F9" thru_hole circle
			(at 17.599914 6.500114 180)
			(size 0.71628 0.71628)
			(drill 0.30988)
			(layers "*.Cu" "*.Mask")
			(remove_unused_layers no)
			(net "Net_8808")
			(clearance 0.0508)
			(thermal_gap 0.0508)
		)
		(pad "F10" thru_hole circle
			(at 19.800062 6.700012 180)
			(size 0.71628 0.71628)
			(drill 0.30988)
			(layers "*.Cu" "*.Mask")
			(remove_unused_layers no)
			(net "Net_8809")
			(clearance 0.0508)
			(thermal_gap 0.0508)
		)
		(pad "G2" thru_hole circle
			(at 2.199894 7.999984 180)
			(size 0.906272 0.906272)
			(drill 0.499872)
			(layers "*.Cu" "*.Mask")
			(remove_unused_layers no)
			(net "GND")
			(clearance 0.0508)
			(thermal_gap 0.0508)
		)
		(pad "G4" thru_hole circle
			(at 6.599936 7.999984 180)
			(size 0.906272 0.906272)
			(drill 0.499872)
			(layers "*.Cu" "*.Mask")
			(remove_unused_layers no)
			(net "GND")
			(clearance 0.0508)
			(thermal_gap 0.0508)
		)
		(pad "G6" thru_hole circle
			(at 10.999978 7.999984 180)
			(size 0.906272 0.906272)
			(drill 0.499872)
			(layers "*.Cu" "*.Mask")
			(remove_unused_layers no)
			(net "GND")
			(clearance 0.0508)
			(thermal_gap 0.0508)
		)
		(pad "G8" thru_hole circle
			(at 15.40002 7.999984 180)
			(size 0.906272 0.906272)
			(drill 0.499872)
			(layers "*.Cu" "*.Mask")
			(remove_unused_layers no)
			(net "GND")
			(clearance 0.0508)
			(thermal_gap 0.0508)
		)
		(pad "G9" thru_hole circle
			(at 17.599914 7.800086 180)
			(size 0.71628 0.71628)
			(drill 0.30988)
			(layers "*.Cu" "*.Mask")
			(remove_unused_layers no)
			(net "Net_8807")
			(clearance 0.0508)
			(thermal_gap 0.0508)
		)
		(pad "G10" thru_hole circle
			(at 19.800062 7.999984 180)
			(size 0.906272 0.906272)
			(drill 0.499872)
			(layers "*.Cu" "*.Mask")
			(remove_unused_layers no)
			(net "GND")
			(clearance 0.0508)
			(thermal_gap 0.0508)
		)
		(pad "H1" thru_hole circle
			(at 0 9.100058 180)
			(size 0.906272 0.906272)
			(drill 0.499872)
			(layers "*.Cu" "*.Mask")
			(remove_unused_layers no)
			(net "GND")
			(clearance 0.0508)
			(thermal_gap 0.0508)
		)
		(pad "H3" thru_hole circle
			(at 4.400042 9.100058 180)
			(size 0.906272 0.906272)
			(drill 0.499872)
			(layers "*.Cu" "*.Mask")
			(remove_unused_layers no)
			(net "GND")
			(clearance 0.0508)
			(thermal_gap 0.0508)
		)
		(pad "H5" thru_hole circle
			(at 8.800084 9.100058 180)
			(size 0.906272 0.906272)
			(drill 0.499872)
			(layers "*.Cu" "*.Mask")
			(remove_unused_layers no)
			(net "GND")
			(clearance 0.0508)
			(thermal_gap 0.0508)
		)
		(pad "H7" thru_hole circle
			(at 13.199872 9.100058 180)
			(size 0.906272 0.906272)
			(drill 0.499872)
			(layers "*.Cu" "*.Mask")
			(remove_unused_layers no)
			(net "GND")
			(clearance 0.0508)
			(thermal_gap 0.0508)
		)
		(pad "H9" thru_hole circle
			(at 17.599914 9.100058 180)
			(size 0.906272 0.906272)
			(drill 0.499872)
			(layers "*.Cu" "*.Mask")
			(remove_unused_layers no)
			(net "GND")
			(clearance 0.0508)
			(thermal_gap 0.0508)
		)
		(pad "H10" thru_hole circle
			(at 19.800062 9.299956 180)
			(size 0.71628 0.71628)
			(drill 0.30988)
			(layers "*.Cu" "*.Mask")
			(remove_unused_layers no)
			(net "Net_8806")
			(clearance 0.0508)
			(thermal_gap 0.0508)
		)
		(pad "I9" thru_hole circle
			(at 17.599914 10.40003 180)
			(size 0.71628 0.71628)
			(drill 0.30988)
			(layers "*.Cu" "*.Mask")
			(remove_unused_layers no)
			(net "Net_8804")
			(clearance 0.0508)
			(thermal_gap 0.0508)
		)
		(pad "I10" thru_hole circle
			(at 19.800062 10.599928 180)
			(size 0.71628 0.71628)
			(drill 0.30988)
			(layers "*.Cu" "*.Mask")
			(remove_unused_layers no)
			(net "Net_8805")
			(clearance 0.0508)
			(thermal_gap 0.0508)
		)
		(pad "J2" thru_hole circle
			(at 2.199894 11.8999 180)
			(size 0.906272 0.906272)
			(drill 0.499872)
			(layers "*.Cu" "*.Mask")
			(remove_unused_layers no)
			(net "GND")
			(clearance 0.0508)
			(thermal_gap 0.0508)
		)
		(pad "J4" thru_hole circle
			(at 6.599936 11.8999 180)
			(size 0.906272 0.906272)
			(drill 0.499872)
			(layers "*.Cu" "*.Mask")
			(remove_unused_layers no)
			(net "GND")
			(clearance 0.0508)
			(thermal_gap 0.0508)
		)
		(pad "J6" thru_hole circle
			(at 10.999978 11.8999 180)
			(size 0.906272 0.906272)
			(drill 0.499872)
			(layers "*.Cu" "*.Mask")
			(remove_unused_layers no)
			(net "GND")
			(clearance 0.0508)
			(thermal_gap 0.0508)
		)
		(pad "J8" thru_hole circle
			(at 15.40002 11.8999 180)
			(size 0.906272 0.906272)
			(drill 0.499872)
			(layers "*.Cu" "*.Mask")
			(remove_unused_layers no)
			(net "GND")
			(clearance 0.0508)
			(thermal_gap 0.0508)
		)
		(pad "J9" thru_hole circle
			(at 17.599914 11.700002 180)
			(size 0.71628 0.71628)
			(drill 0.30988)
			(layers "*.Cu" "*.Mask")
			(remove_unused_layers no)
			(net "Net_8803")
			(clearance 0.0508)
			(thermal_gap 0.0508)
		)
		(pad "J10" thru_hole circle
			(at 19.800062 11.8999 180)
			(size 0.906272 0.906272)
			(drill 0.499872)
			(layers "*.Cu" "*.Mask")
			(remove_unused_layers no)
			(net "GND")
			(clearance 0.0508)
			(thermal_gap 0.0508)
		)
		(pad "K1" thru_hole circle
			(at 0 12.999974 180)
			(size 0.906272 0.906272)
			(drill 0.499872)
			(layers "*.Cu" "*.Mask")
			(remove_unused_layers no)
			(net "GND")
			(clearance 0.0508)
			(thermal_gap 0.0508)
		)
		(pad "K3" thru_hole circle
			(at 4.400042 12.999974 180)
			(size 0.906272 0.906272)
			(drill 0.499872)
			(layers "*.Cu" "*.Mask")
			(remove_unused_layers no)
			(net "GND")
			(clearance 0.0508)
			(thermal_gap 0.0508)
		)
		(pad "K5" thru_hole circle
			(at 8.800084 12.999974 180)
			(size 0.906272 0.906272)
			(drill 0.499872)
			(layers "*.Cu" "*.Mask")
			(remove_unused_layers no)
			(net "GND")
			(clearance 0.0508)
			(thermal_gap 0.0508)
		)
		(pad "K7" thru_hole circle
			(at 13.199872 12.999974 180)
			(size 0.906272 0.906272)
			(drill 0.499872)
			(layers "*.Cu" "*.Mask")
			(remove_unused_layers no)
			(net "GND")
			(clearance 0.0508)
			(thermal_gap 0.0508)
		)
		(pad "K9" thru_hole circle
			(at 17.599914 12.999974 180)
			(size 0.906272 0.906272)
			(drill 0.499872)
			(layers "*.Cu" "*.Mask")
			(remove_unused_layers no)
			(net "GND")
			(clearance 0.0508)
			(thermal_gap 0.0508)
		)
		(pad "K10" thru_hole circle
			(at 19.800062 13.199872 180)
			(size 0.71628 0.71628)
			(drill 0.30988)
			(layers "*.Cu" "*.Mask")
			(remove_unused_layers no)
			(net "Net_8802")
			(clearance 0.0508)
			(thermal_gap 0.0508)
		)
		(pad "L9" thru_hole circle
			(at 17.599914 14.299946 180)
			(size 0.71628 0.71628)
			(drill 0.30988)
			(layers "*.Cu" "*.Mask")
			(remove_unused_layers no)
			(net "Net_8800")
			(clearance 0.0508)
			(thermal_gap 0.0508)
		)
		(pad "L10" thru_hole circle
			(at 19.800062 14.500098 180)
			(size 0.71628 0.71628)
			(drill 0.30988)
			(layers "*.Cu" "*.Mask")
			(remove_unused_layers no)
			(net "Net_8801")
			(clearance 0.0508)
			(thermal_gap 0.0508)
		)
		(pad "M1_2" thru_hole circle
			(at 2.199894 15.80007 180)
			(size 0.906272 0.906272)
			(drill 0.499872)
			(layers "*.Cu" "*.Mask")
			(remove_unused_layers no)
			(net "GND")
			(clearance 0.0508)
			(thermal_gap 0.0508)
		)
		(pad "M1_4" thru_hole circle
			(at 6.599936 15.80007 180)
			(size 0.906272 0.906272)
			(drill 0.499872)
			(layers "*.Cu" "*.Mask")
			(remove_unused_layers no)
			(net "GND")
			(clearance 0.0508)
			(thermal_gap 0.0508)
		)
		(pad "M1_6" thru_hole circle
			(at 10.999978 15.80007 180)
			(size 0.906272 0.906272)
			(drill 0.499872)
			(layers "*.Cu" "*.Mask")
			(remove_unused_layers no)
			(net "GND")
			(clearance 0.0508)
			(thermal_gap 0.0508)
		)
		(pad "M1_8" thru_hole circle
			(at 15.40002 15.80007 180)
			(size 0.906272 0.906272)
			(drill 0.499872)
			(layers "*.Cu" "*.Mask")
			(remove_unused_layers no)
			(net "GND")
			(clearance 0.0508)
			(thermal_gap 0.0508)
		)
		(pad "M1_10" thru_hole circle
			(at 19.800062 15.80007 180)
			(size 0.906272 0.906272)
			(drill 0.499872)
			(layers "*.Cu" "*.Mask")
			(remove_unused_layers no)
			(net "GND")
			(clearance 0.0508)
			(thermal_gap 0.0508)
		)
		(pad "M2_2" thru_hole circle
			(at 2.199894 26.2001 180)
			(size 0.906272 0.906272)
			(drill 0.499872)
			(layers "*.Cu" "*.Mask")
			(remove_unused_layers no)
			(net "GND")
			(clearance 0.0508)
			(thermal_gap 0.0508)
		)
		(pad "M2_4" thru_hole circle
			(at 6.599936 26.2001 180)
			(size 0.906272 0.906272)
			(drill 0.499872)
			(layers "*.Cu" "*.Mask")
			(remove_unused_layers no)
			(net "GND")
			(clearance 0.0508)
			(thermal_gap 0.0508)
		)
		(pad "M2_6" thru_hole circle
			(at 10.999978 26.2001 180)
			(size 0.906272 0.906272)
			(drill 0.499872)
			(layers "*.Cu" "*.Mask")
			(remove_unused_layers no)
			(net "GND")
			(clearance 0.0508)
			(thermal_gap 0.0508)
		)
		(pad "M2_8" thru_hole circle
			(at 15.40002 26.2001 180)
			(size 0.906272 0.906272)
			(drill 0.499872)
			(layers "*.Cu" "*.Mask")
			(remove_unused_layers no)
			(net "GND")
			(clearance 0.0508)
			(thermal_gap 0.0508)
		)
		(pad "M2_10" thru_hole circle
			(at 19.800062 26.2001 180)
			(size 0.906272 0.906272)
			(drill 0.499872)
			(layers "*.Cu" "*.Mask")
			(remove_unused_layers no)
			(net "GND")
			(clearance 0.0508)
			(thermal_gap 0.0508)
		)
		(pad "M9" thru_hole circle
			(at 17.599914 15.599918 180)
			(size 0.71628 0.71628)
			(drill 0.30988)
			(layers "*.Cu" "*.Mask")
			(remove_unused_layers no)
			(net "Net_8799")
			(clearance 0.0508)
			(thermal_gap 0.0508)
		)
		(pad "N1_1" thru_hole circle
			(at 0 16.89989 180)
			(size 0.906272 0.906272)
			(drill 0.499872)
			(layers "*.Cu" "*.Mask")
			(remove_unused_layers no)
			(net "GND")
			(clearance 0.0508)
			(thermal_gap 0.0508)
		)
		(pad "N1_3" thru_hole circle
			(at 4.400042 16.89989 180)
			(size 0.906272 0.906272)
			(drill 0.499872)
			(layers "*.Cu" "*.Mask")
			(remove_unused_layers no)
			(net "GND")
			(clearance 0.0508)
			(thermal_gap 0.0508)
		)
		(pad "N1_5" thru_hole circle
			(at 8.800084 16.89989 180)
			(size 0.906272 0.906272)
			(drill 0.499872)
			(layers "*.Cu" "*.Mask")
			(remove_unused_layers no)
			(net "GND")
			(clearance 0.0508)
			(thermal_gap 0.0508)
		)
		(pad "N1_7" thru_hole circle
			(at 13.199872 16.89989 180)
			(size 0.906272 0.906272)
			(drill 0.499872)
			(layers "*.Cu" "*.Mask")
			(remove_unused_layers no)
			(net "GND")
			(clearance 0.0508)
			(thermal_gap 0.0508)
		)
		(pad "N1_9" thru_hole circle
			(at 17.599914 16.89989 180)
			(size 0.906272 0.906272)
			(drill 0.499872)
			(layers "*.Cu" "*.Mask")
			(remove_unused_layers no)
			(net "GND")
			(clearance 0.0508)
			(thermal_gap 0.0508)
		)
		(pad "N2_1" thru_hole circle
			(at 0 27.29992 180)
			(size 0.906272 0.906272)
			(drill 0.499872)
			(layers "*.Cu" "*.Mask")
			(remove_unused_layers no)
			(net "GND")
			(clearance 0.0508)
			(thermal_gap 0.0508)
		)
	)
)
